(kicad_pcb
	(version 20260206)
	(generator "pcbnew")
	(generator_version "10.0")
	(general
		(thickness 1.6)
		(legacy_teardrops no)
	)
	(paper "A4")
	(title_block
		(title "peb — Lightning_PEB_BRD.brd")
		(comment 1 "Lightning (Wiwynn / Facebook NVMe JBOF) / footprints 1397-1403 of 2563")
	)
	(layers
		(0 "F.Cu" signal "TOP")
		(4 "In1.Cu" signal "L2GND")
		(6 "In2.Cu" signal "L3")
		(8 "In3.Cu" signal "L4VCC")
		(10 "In4.Cu" signal "L5VCC")
		(12 "In5.Cu" signal "L6")
		(14 "In6.Cu" signal "L7GND")
		(2 "B.Cu" signal "BOTTOM")
		(9 "F.Adhes" user "F.Adhesive")
		(11 "B.Adhes" user "B.Adhesive")
		(13 "F.Paste" user "Package Geometry/Pastemask Top")
		(15 "B.Paste" user "Package Geometry/Pastemask Bottom")
		(5 "F.SilkS" user "Ref Des/Silkscreen Top")
		(7 "B.SilkS" user "Ref Des/Silkscreen Bottom")
		(1 "F.Mask" user "Board Geometry/Soldermask Top")
		(3 "B.Mask" user "Board Geometry/Soldermask Bottom")
		(17 "Dwgs.User" user "User.Drawings")
		(19 "Cmts.User" user "User.Comments")
		(21 "Eco1.User" user "User.Eco1")
		(23 "Eco2.User" user "User.Eco2")
		(25 "Edge.Cuts" user "Board Geometry/Outline")
		(27 "Margin" user)
		(31 "F.CrtYd" user "Package Geometry/Place Bound Top")
		(29 "B.CrtYd" user "Package Geometry/Place Bound Bottom")
		(35 "F.Fab" user "Ref Des/Assembly Top")
		(33 "B.Fab" user "Ref Des/Assembly Bottom")
	)
	(footprint ""
		(layer "F.Cu")
		(at 183.09336 -14.76756)
		(property "Reference" "R211"
			(at 0 0 0)
			(layer "F.SilkS")
			(hide yes)
			(effects
				(font
					(size 1.27 1.27)
				)
			)
		)
		(property "Value" "4K7R2F-GP"
			(at 0.064008 -3.993896 0)
			(unlocked yes)
			(layer "F.Fab")
			(hide yes)
			(effects
				(font
					(size 1.016 1.016)
					(thickness 0.1524)
				)
			)
		)
		(property "Device Type" "R402H16"
			(at 0.064008 -5.517896 0)
			(unlocked yes)
			(layer "F.Fab")
			(hide yes)
			(effects
				(font
					(size 1.016 1.016)
					(thickness 0.1524)
				)
			)
		)
		(duplicate_pad_numbers_are_jumpers no)
		(fp_line
			(start -0.508 -0.9398)
			(end -0.508 0.9398)
			(stroke
				(width 0.1524)
				(type default)
			)
			(layer "F.SilkS")
		)
		(fp_line
			(start 0.508 -0.9398)
			(end -0.508 -0.9398)
			(stroke
				(width 0.1524)
				(type default)
			)
			(layer "F.SilkS")
		)
		(fp_rect
			(start -0.508 0.9398)
			(end 0.508 -0.9398)
			(stroke
				(width 0)
				(type default)
			)
			(fill no)
			(layer "F.CrtYd")
		)
		(fp_rect
			(start -0.508 0.9398)
			(end 0.508 -0.9398)
			(stroke
				(width 0)
				(type default)
			)
			(fill no)
			(layer "F.Fab")
		)
		(pad "1" smd custom
			(at 0 -0.4445)
			(size 0.1397 0.1397)
			(layers "F.Cu" "F.Mask" "F.Paste")
			(net "CLK_P_4_R")
			(options
				(clearance outline)
				(anchor circle)
			)
			(primitives
				(gr_poly
					(pts
						(arc
							(start -0.1778 -0.2794)
							(mid -0.249642 -0.249642)
							(end -0.2794 -0.1778)
						)
						(arc
							(start -0.2794 0.1778)
							(mid -0.249642 0.249642)
							(end -0.1778 0.2794)
						)
						(arc
							(start 0.1778 0.2794)
							(mid 0.249642 0.249642)
							(end 0.2794 0.1778)
						)
						(arc
							(start 0.2794 -0.1778)
							(mid 0.249642 -0.249642)
							(end 0.1778 -0.2794)
						)
					)
					(width 0)
					(fill yes)
				)
			)
		)
		(pad "2" smd custom
			(at 0 0.4445)
			(size 0.1397 0.1397)
			(layers "F.Cu" "F.Mask" "F.Paste")
			(net "GND")
			(options
				(clearance outline)
				(anchor circle)
			)
			(primitives
				(gr_poly
					(pts
						(arc
							(start -0.1778 -0.2794)
							(mid -0.249642 -0.249642)
							(end -0.2794 -0.1778)
						)
						(arc
							(start -0.2794 0.1778)
							(mid -0.249642 0.249642)
							(end -0.1778 0.2794)
						)
						(arc
							(start 0.1778 0.2794)
							(mid 0.249642 0.249642)
							(end 0.2794 0.1778)
						)
						(arc
							(start 0.2794 -0.1778)
							(mid 0.249642 -0.249642)
							(end 0.1778 -0.2794)
						)
					)
					(width 0)
					(fill yes)
				)
			)
		)
	)
	(footprint ""
		(layer "F.Cu")
		(at 14.8082 -83.6168)
		(property "Reference" "R403"
			(at 0 0 0)
			(layer "F.SilkS")
			(hide yes)
			(effects
				(font
					(size 1.27 1.27)
				)
			)
		)
		(property "Value" "3K3R2F-2-GP"
			(at 0.064008 -3.993896 0)
			(unlocked yes)
			(layer "F.Fab")
			(hide yes)
			(effects
				(font
					(size 1.016 1.016)
					(thickness 0.1524)
				)
			)
		)
		(property "Device Type" "R402H16"
			(at 0.064008 -5.517896 0)
			(unlocked yes)
			(layer "F.Fab")
			(hide yes)
			(effects
				(font
					(size 1.016 1.016)
					(thickness 0.1524)
				)
			)
		)
		(duplicate_pad_numbers_are_jumpers no)
		(fp_line
			(start -0.508 -0.9398)
			(end -0.508 0.9398)
			(stroke
				(width 0.1524)
				(type default)
			)
			(layer "F.SilkS")
		)
		(fp_line
			(start 0.508 -0.9398)
			(end -0.508 -0.9398)
			(stroke
				(width 0.1524)
				(type default)
			)
			(layer "F.SilkS")
		)
		(fp_rect
			(start -0.508 0.9398)
			(end 0.508 -0.9398)
			(stroke
				(width 0)
				(type default)
			)
			(fill no)
			(layer "F.CrtYd")
		)
		(fp_rect
			(start -0.508 0.9398)
			(end 0.508 -0.9398)
			(stroke
				(width 0)
				(type default)
			)
			(fill no)
			(layer "F.Fab")
		)
		(pad "1" smd custom
			(at 0 -0.4445)
			(size 0.1397 0.1397)
			(layers "F.Cu" "F.Mask" "F.Paste")
			(net "P3V3_STBY")
			(options
				(clearance outline)
				(anchor circle)
			)
			(primitives
				(gr_poly
					(pts
						(arc
							(start -0.1778 -0.2794)
							(mid -0.249642 -0.249642)
							(end -0.2794 -0.1778)
						)
						(arc
							(start -0.2794 0.1778)
							(mid -0.249642 0.249642)
							(end -0.1778 0.2794)
						)
						(arc
							(start 0.1778 0.2794)
							(mid 0.249642 0.249642)
							(end 0.2794 0.1778)
						)
						(arc
							(start 0.2794 -0.1778)
							(mid 0.249642 -0.249642)
							(end 0.1778 -0.2794)
						)
					)
					(width 0)
					(fill yes)
				)
			)
		)
		(pad "2" smd custom
			(at 0 0.4445)
			(size 0.1397 0.1397)
			(layers "F.Cu" "F.Mask" "F.Paste")
			(net "NIC_JTDI")
			(options
				(clearance outline)
				(anchor circle)
			)
			(primitives
				(gr_poly
					(pts
						(arc
							(start -0.1778 -0.2794)
							(mid -0.249642 -0.249642)
							(end -0.2794 -0.1778)
						)
						(arc
							(start -0.2794 0.1778)
							(mid -0.249642 0.249642)
							(end -0.1778 0.2794)
						)
						(arc
							(start 0.1778 0.2794)
							(mid 0.249642 0.249642)
							(end 0.2794 0.1778)
						)
						(arc
							(start 0.2794 -0.1778)
							(mid 0.249642 -0.249642)
							(end 0.1778 -0.2794)
						)
					)
					(width 0)
					(fill yes)
				)
			)
		)
	)
	(footprint ""
		(layer "F.Cu")
		(at 134.342124 -208.889092 180)
		(property "Reference" "R7940"
			(at 0 0 180)
			(layer "F.SilkS")
			(hide yes)
			(effects
				(font
					(size 1.27 1.27)
				)
			)
		)
		(property "Value" "0R2J-2-GP"
			(at 0.064008 -3.993896 180)
			(unlocked yes)
			(layer "F.Fab")
			(hide yes)
			(effects
				(font
					(size 1.016 1.016)
					(thickness 0.1524)
				)
			)
		)
		(property "Device Type" "R402H16"
			(at 0.064008 -5.517896 180)
			(unlocked yes)
			(layer "F.Fab")
			(hide yes)
			(effects
				(font
					(size 1.016 1.016)
					(thickness 0.1524)
				)
			)
		)
		(duplicate_pad_numbers_are_jumpers no)
		(fp_line
			(start 0.508 -0.9398)
			(end -0.508 -0.9398)
			(stroke
				(width 0.1524)
				(type default)
			)
			(layer "F.SilkS")
		)
		(fp_line
			(start -0.508 -0.9398)
			(end -0.508 0.9398)
			(stroke
				(width 0.1524)
				(type default)
			)
			(layer "F.SilkS")
		)
		(fp_rect
			(start -0.508 0.9398)
			(end 0.508 -0.9398)
			(stroke
				(width 0)
				(type default)
			)
			(fill no)
			(layer "F.CrtYd")
		)
		(fp_rect
			(start -0.508 0.9398)
			(end 0.508 -0.9398)
			(stroke
				(width 0)
				(type default)
			)
			(fill no)
			(layer "F.Fab")
		)
		(pad "1" smd custom
			(at 0 -0.4445 180)
			(size 0.1397 0.1397)
			(layers "F.Cu" "F.Mask" "F.Paste")
			(net "SSD_ATNLED#6")
			(options
				(clearance outline)
				(anchor circle)
			)
			(primitives
				(gr_poly
					(pts
						(arc
							(start -0.1778 -0.2794)
							(mid -0.249642 -0.249642)
							(end -0.2794 -0.1778)
						)
						(arc
							(start -0.2794 0.1778)
							(mid -0.249642 0.249642)
							(end -0.1778 0.2794)
						)
						(arc
							(start 0.1778 0.2794)
							(mid 0.249642 0.249642)
							(end 0.2794 0.1778)
						)
						(arc
							(start 0.2794 -0.1778)
							(mid 0.249642 -0.249642)
							(end 0.1778 -0.2794)
						)
					)
					(width 0)
					(fill yes)
				)
			)
		)
		(pad "2" smd custom
			(at 0 0.4445 180)
			(size 0.1397 0.1397)
			(layers "F.Cu" "F.Mask" "F.Paste")
			(net "SSD_ATNLED#6_R")
			(options
				(clearance outline)
				(anchor circle)
			)
			(primitives
				(gr_poly
					(pts
						(arc
							(start -0.1778 -0.2794)
							(mid -0.249642 -0.249642)
							(end -0.2794 -0.1778)
						)
						(arc
							(start -0.2794 0.1778)
							(mid -0.249642 0.249642)
							(end -0.1778 0.2794)
						)
						(arc
							(start 0.1778 0.2794)
							(mid 0.249642 0.249642)
							(end 0.2794 0.1778)
						)
						(arc
							(start 0.2794 -0.1778)
							(mid 0.249642 -0.249642)
							(end 0.1778 -0.2794)
						)
					)
					(width 0)
					(fill yes)
				)
			)
		)
	)
	(footprint ""
		(layer "F.Cu")
		(at 182.62727 -3.800856 -90)
		(property "Reference" "R716"
			(at 0 0 270)
			(layer "F.SilkS")
			(hide yes)
			(effects
				(font
					(size 1.27 1.27)
				)
			)
		)
		(property "Value" "0R2J-2-GP"
			(at 0.064008 -3.993896 270)
			(unlocked yes)
			(layer "F.Fab")
			(hide yes)
			(effects
				(font
					(size 1.016 1.016)
					(thickness 0.1524)
				)
			)
		)
		(property "Device Type" "R402H16"
			(at 0.064008 -5.517896 270)
			(unlocked yes)
			(layer "F.Fab")
			(hide yes)
			(effects
				(font
					(size 1.016 1.016)
					(thickness 0.1524)
				)
			)
		)
		(duplicate_pad_numbers_are_jumpers no)
		(fp_line
			(start -0.508 -0.9398)
			(end -0.508 0.9398)
			(stroke
				(width 0.1524)
				(type default)
			)
			(layer "F.SilkS")
		)
		(fp_line
			(start 0.508 -0.9398)
			(end -0.508 -0.9398)
			(stroke
				(width 0.1524)
				(type default)
			)
			(layer "F.SilkS")
		)
		(fp_rect
			(start -0.508 0.9398)
			(end 0.508 -0.9398)
			(stroke
				(width 0)
				(type default)
			)
			(fill no)
			(layer "F.CrtYd")
		)
		(fp_rect
			(start -0.508 0.9398)
			(end 0.508 -0.9398)
			(stroke
				(width 0)
				(type default)
			)
			(fill no)
			(layer "F.Fab")
		)
		(pad "1" smd custom
			(at 0 -0.4445 270)
			(size 0.1397 0.1397)
			(layers "F.Cu" "F.Mask" "F.Paste")
			(net "HOST3_RST_N_C")
			(options
				(clearance outline)
				(anchor circle)
			)
			(primitives
				(gr_poly
					(pts
						(arc
							(start -0.1778 -0.2794)
							(mid -0.249642 -0.249642)
							(end -0.2794 -0.1778)
						)
						(arc
							(start -0.2794 0.1778)
							(mid -0.249642 0.249642)
							(end -0.1778 0.2794)
						)
						(arc
							(start 0.1778 0.2794)
							(mid 0.249642 0.249642)
							(end 0.2794 0.1778)
						)
						(arc
							(start 0.2794 -0.1778)
							(mid 0.249642 -0.249642)
							(end 0.1778 -0.2794)
						)
					)
					(width 0)
					(fill yes)
				)
			)
		)
		(pad "2" smd custom
			(at 0 0.4445 270)
			(size 0.1397 0.1397)
			(layers "F.Cu" "F.Mask" "F.Paste")
			(net "P3V3_STBY")
			(options
				(clearance outline)
				(anchor circle)
			)
			(primitives
				(gr_poly
					(pts
						(arc
							(start -0.1778 -0.2794)
							(mid -0.249642 -0.249642)
							(end -0.2794 -0.1778)
						)
						(arc
							(start -0.2794 0.1778)
							(mid -0.249642 0.249642)
							(end -0.1778 0.2794)
						)
						(arc
							(start 0.1778 0.2794)
							(mid 0.249642 0.249642)
							(end 0.2794 0.1778)
						)
						(arc
							(start 0.2794 -0.1778)
							(mid 0.249642 -0.249642)
							(end 0.1778 -0.2794)
						)
					)
					(width 0)
					(fill yes)
				)
			)
		)
	)
	(footprint ""
		(layer "F.Cu")
		(at 223.877124 -190.601092)
		(property "Reference" "R7929"
			(at 0 0 0)
			(layer "F.SilkS")
			(hide yes)
			(effects
				(font
					(size 1.27 1.27)
				)
			)
		)
		(property "Value" "0R2J-2-GP"
			(at 0.064008 -3.993896 0)
			(unlocked yes)
			(layer "F.Fab")
			(hide yes)
			(effects
				(font
					(size 1.016 1.016)
					(thickness 0.1524)
				)
			)
		)
		(property "Device Type" "R402H16"
			(at 0.064008 -5.517896 0)
			(unlocked yes)
			(layer "F.Fab")
			(hide yes)
			(effects
				(font
					(size 1.016 1.016)
					(thickness 0.1524)
				)
			)
		)
		(duplicate_pad_numbers_are_jumpers no)
		(fp_line
			(start -0.508 -0.9398)
			(end -0.508 0.9398)
			(stroke
				(width 0.1524)
				(type default)
			)
			(layer "F.SilkS")
		)
		(fp_line
			(start 0.508 -0.9398)
			(end -0.508 -0.9398)
			(stroke
				(width 0.1524)
				(type default)
			)
			(layer "F.SilkS")
		)
		(fp_rect
			(start -0.508 0.9398)
			(end 0.508 -0.9398)
			(stroke
				(width 0)
				(type default)
			)
			(fill no)
			(layer "F.CrtYd")
		)
		(fp_rect
			(start -0.508 0.9398)
			(end 0.508 -0.9398)
			(stroke
				(width 0)
				(type default)
			)
			(fill no)
			(layer "F.Fab")
		)
		(pad "1" smd custom
			(at 0 -0.4445)
			(size 0.1397 0.1397)
			(layers "F.Cu" "F.Mask" "F.Paste")
			(net "SSD_PRSNT#8")
			(options
				(clearance outline)
				(anchor circle)
			)
			(primitives
				(gr_poly
					(pts
						(arc
							(start -0.1778 -0.2794)
							(mid -0.249642 -0.249642)
							(end -0.2794 -0.1778)
						)
						(arc
							(start -0.2794 0.1778)
							(mid -0.249642 0.249642)
							(end -0.1778 0.2794)
						)
						(arc
							(start 0.1778 0.2794)
							(mid 0.249642 0.249642)
							(end 0.2794 0.1778)
						)
						(arc
							(start 0.2794 -0.1778)
							(mid 0.249642 -0.249642)
							(end 0.1778 -0.2794)
						)
					)
					(width 0)
					(fill yes)
				)
			)
		)
		(pad "2" smd custom
			(at 0 0.4445)
			(size 0.1397 0.1397)
			(layers "F.Cu" "F.Mask" "F.Paste")
			(net "SSD_PRSNT#8_R")
			(options
				(clearance outline)
				(anchor circle)
			)
			(primitives
				(gr_poly
					(pts
						(arc
							(start -0.1778 -0.2794)
							(mid -0.249642 -0.249642)
							(end -0.2794 -0.1778)
						)
						(arc
							(start -0.2794 0.1778)
							(mid -0.249642 0.249642)
							(end -0.1778 0.2794)
						)
						(arc
							(start 0.1778 0.2794)
							(mid 0.249642 0.249642)
							(end 0.2794 0.1778)
						)
						(arc
							(start 0.2794 -0.1778)
							(mid 0.249642 -0.249642)
							(end 0.1778 -0.2794)
						)
					)
					(width 0)
					(fill yes)
				)
			)
		)
	)
	(footprint ""
		(layer "F.Cu")
		(at 141.798802 -34.34588)
		(property "Reference" "R302"
			(at 0 0 0)
			(layer "F.SilkS")
			(hide yes)
			(effects
				(font
					(size 1.27 1.27)
				)
			)
		)
		(property "Value" "0R2J-2-GP"
			(at 0.064008 -3.993896 0)
			(unlocked yes)
			(layer "F.Fab")
			(hide yes)
			(effects
				(font
					(size 1.016 1.016)
					(thickness 0.1524)
				)
			)
		)
		(property "Device Type" "R402H16"
			(at 0.064008 -5.517896 0)
			(unlocked yes)
			(layer "F.Fab")
			(hide yes)
			(effects
				(font
					(size 1.016 1.016)
					(thickness 0.1524)
				)
			)
		)
		(duplicate_pad_numbers_are_jumpers no)
		(fp_line
			(start -0.508 -0.9398)
			(end -0.508 0.9398)
			(stroke
				(width 0.1524)
				(type default)
			)
			(layer "F.SilkS")
		)
		(fp_line
			(start 0.508 -0.9398)
			(end -0.508 -0.9398)
			(stroke
				(width 0.1524)
				(type default)
			)
			(layer "F.SilkS")
		)
		(fp_rect
			(start -0.508 0.9398)
			(end 0.508 -0.9398)
			(stroke
				(width 0)
				(type default)
			)
			(fill no)
			(layer "F.CrtYd")
		)
		(fp_rect
			(start -0.508 0.9398)
			(end 0.508 -0.9398)
			(stroke
				(width 0)
				(type default)
			)
			(fill no)
			(layer "F.Fab")
		)
		(pad "1" smd custom
			(at 0 -0.4445)
			(size 0.1397 0.1397)
			(layers "F.Cu" "F.Mask" "F.Paste")
			(net "CLK_P_2_R")
			(options
				(clearance outline)
				(anchor circle)
			)
			(primitives
				(gr_poly
					(pts
						(arc
							(start -0.1778 -0.2794)
							(mid -0.249642 -0.249642)
							(end -0.2794 -0.1778)
						)
						(arc
							(start -0.2794 0.1778)
							(mid -0.249642 0.249642)
							(end -0.1778 0.2794)
						)
						(arc
							(start 0.1778 0.2794)
							(mid 0.249642 0.249642)
							(end 0.2794 0.1778)
						)
						(arc
							(start 0.2794 -0.1778)
							(mid 0.249642 -0.249642)
							(end 0.1778 -0.2794)
						)
					)
					(width 0)
					(fill yes)
				)
			)
		)
		(pad "2" smd custom
			(at 0 0.4445)
			(size 0.1397 0.1397)
			(layers "F.Cu" "F.Mask" "F.Paste")
			(net "CLK_P_2")
			(options
				(clearance outline)
				(anchor circle)
			)
			(primitives
				(gr_poly
					(pts
						(arc
							(start -0.1778 -0.2794)
							(mid -0.249642 -0.249642)
							(end -0.2794 -0.1778)
						)
						(arc
							(start -0.2794 0.1778)
							(mid -0.249642 0.249642)
							(end -0.1778 0.2794)
						)
						(arc
							(start 0.1778 0.2794)
							(mid 0.249642 0.249642)
							(end 0.2794 0.1778)
						)
						(arc
							(start 0.2794 -0.1778)
							(mid 0.249642 -0.249642)
							(end 0.1778 -0.2794)
						)
					)
					(width 0)
					(fill yes)
				)
			)
		)
	)
	(footprint ""
		(layer "F.Cu")
		(at 133.326124 -208.889092 180)
		(property "Reference" "R7956"
			(at 0 0 180)
			(layer "F.SilkS")
			(hide yes)
			(effects
				(font
					(size 1.27 1.27)
				)
			)
		)
		(property "Value" "0R2J-2-GP"
			(at 0.064008 -3.993896 180)
			(unlocked yes)
			(layer "F.Fab")
			(hide yes)
			(effects
				(font
					(size 1.016 1.016)
					(thickness 0.1524)
				)
			)
		)
		(property "Device Type" "R402H16"
			(at 0.064008 -5.517896 180)
			(unlocked yes)
			(layer "F.Fab")
			(hide yes)
			(effects
				(font
					(size 1.016 1.016)
					(thickness 0.1524)
				)
			)
		)
		(duplicate_pad_numbers_are_jumpers no)
		(fp_line
			(start 0.508 -0.9398)
			(end -0.508 -0.9398)
			(stroke
				(width 0.1524)
				(type default)
			)
			(layer "F.SilkS")
		)
		(fp_line
			(start -0.508 -0.9398)
			(end -0.508 0.9398)
			(stroke
				(width 0.1524)
				(type default)
			)
			(layer "F.SilkS")
		)
		(fp_rect
			(start -0.508 0.9398)
			(end 0.508 -0.9398)
			(stroke
				(width 0)
				(type default)
			)
			(fill no)
			(layer "F.CrtYd")
		)
		(fp_rect
			(start -0.508 0.9398)
			(end 0.508 -0.9398)
			(stroke
				(width 0)
				(type default)
			)
			(fill no)
			(layer "F.Fab")
		)
		(pad "1" smd custom
			(at 0 -0.4445 180)
			(size 0.1397 0.1397)
			(layers "F.Cu" "F.Mask" "F.Paste")
			(net "SSD_PWREN6")
			(options
				(clearance outline)
				(anchor circle)
			)
			(primitives
				(gr_poly
					(pts
						(arc
							(start -0.1778 -0.2794)
							(mid -0.249642 -0.249642)
							(end -0.2794 -0.1778)
						)
						(arc
							(start -0.2794 0.1778)
							(mid -0.249642 0.249642)
							(end -0.1778 0.2794)
						)
						(arc
							(start 0.1778 0.2794)
							(mid 0.249642 0.249642)
							(end 0.2794 0.1778)
						)
						(arc
							(start 0.2794 -0.1778)
							(mid 0.249642 -0.249642)
							(end 0.1778 -0.2794)
						)
					)
					(width 0)
					(fill yes)
				)
			)
		)
		(pad "2" smd custom
			(at 0 0.4445 180)
			(size 0.1397 0.1397)
			(layers "F.Cu" "F.Mask" "F.Paste")
			(net "SSD_PWREN6_R")
			(options
				(clearance outline)
				(anchor circle)
			)
			(primitives
				(gr_poly
					(pts
						(arc
							(start -0.1778 -0.2794)
							(mid -0.249642 -0.249642)
							(end -0.2794 -0.1778)
						)
						(arc
							(start -0.2794 0.1778)
							(mid -0.249642 0.249642)
							(end -0.1778 0.2794)
						)
						(arc
							(start 0.1778 0.2794)
							(mid 0.249642 0.249642)
							(end 0.2794 0.1778)
						)
						(arc
							(start 0.2794 -0.1778)
							(mid 0.249642 -0.249642)
							(end 0.1778 -0.2794)
						)
					)
					(width 0)
					(fill yes)
				)
			)
		)
	)
)
